# BASEBOARD_FAB2 (Tioga Pass) — schematic netlist excerpt (pin names and nets, part order shuffled) for the footprints in the layout excerpt that follows; sources: Cadence DE-HDL packaged netlist, KiCad conversion of Wiwynn_Tioga_Pass_MB.brd

C7C12  CAP  1.0UF 16V 10% X6S  pkg 0402  page 212 : A = VR_FET_SW_P12V_STBY_PVCCIO_CPU0 ; B = GND
C8A8  CAP_A  0.1UF 16V 10% X7R  pkg 0402V  page 235 : A = VR_PVNN_P1V05_PCH_VD12 ; B = GND
R7W14  RES  0.0 5% CHIP  pkg 0402  page 120 : A = FM_BMC_READY_N ; B = FM_BMC_READY_R1_N

(kicad_pcb
	(version 20260206)
	(generator "pcbnew")
	(generator_version "10.0")
	(general
		(thickness 1.6)
		(legacy_teardrops no)
	)
	(paper "A4")
	(title_block
		(title "Wiwynn_Tioga_Pass_MB.brd")
		(comment 1 "Tioga Pass / footprints 2003-2005 of 4770")
	)
	(layers
		(0 "F.Cu" signal "TOP")
		(4 "In1.Cu" signal "L2GND")
		(6 "In2.Cu" signal "L3")
		(8 "In3.Cu" signal "L4GND")
		(10 "In4.Cu" signal "L5")
		(12 "In5.Cu" signal "L6GND")
		(14 "In6.Cu" signal "L7VCC")
		(16 "In7.Cu" signal "L8VCC")
		(18 "In8.Cu" signal "L9GND")
		(20 "In9.Cu" signal "L10")
		(22 "In10.Cu" signal "L11GND")
		(24 "In11.Cu" signal "L12")
		(26 "In12.Cu" signal "L13GND")
		(2 "B.Cu" signal "BOTTOM")
		(9 "F.Adhes" user "F.Adhesive")
		(11 "B.Adhes" user "B.Adhesive")
		(13 "F.Paste" user "Package Geometry/Pastemask Top")
		(15 "B.Paste" user "Package Geometry/Pastemask Bottom")
		(5 "F.SilkS" user "Ref Des/Silkscreen Top")
		(7 "B.SilkS" user "Ref Des/Silkscreen Bottom")
		(1 "F.Mask" user "Board Geometry/Soldermask Top")
		(3 "B.Mask" user "Board Geometry/Soldermask Bottom")
		(17 "Dwgs.User" user "User.Drawings")
		(19 "Cmts.User" user "User.Comments")
		(21 "Eco1.User" user "User.Eco1")
		(23 "Eco2.User" user "User.Eco2")
		(25 "Edge.Cuts" user "Board Geometry/Outline")
		(27 "Margin" user)
		(31 "F.CrtYd" user "Package Geometry/Place Bound Top")
		(29 "B.CrtYd" user "Package Geometry/Place Bound Bottom")
		(35 "F.Fab" user "Ref Des/Assembly Top")
		(33 "B.Fab" user "Ref Des/Assembly Bottom")
	)
	(footprint ""
		(layer "F.Cu")
		(at 391.795 -151.236426)
		(property "Reference" "C8A8"
			(at 0 0 0)
			(layer "F.SilkS")
			(hide yes)
			(effects
				(font
					(size 1.27 1.27)
				)
			)
		)
		(property "Value" ""
			(at 0 0 0)
			(layer "F.Fab")
			(effects
				(font
					(size 1.27 1.27)
				)
			)
		)
		(duplicate_pad_numbers_are_jumpers no)
		(fp_poly
			(pts
				(xy 0.3048 -0.1016) (xy 0.3048 0.9906) (xy -0.3048 0.9906) (xy -0.3048 -0.1016)
			)
			(stroke
				(width 0)
				(type default)
			)
			(fill no)
			(layer "F.CrtYd")
		)
		(fp_line
			(start -0.3048 -0.1016)
			(end -0.3048 0.9906)
			(stroke
				(width 0.1)
				(type default)
			)
			(layer "F.Fab")
		)
		(fp_line
			(start -0.3048 0.9906)
			(end 0.3048 0.9906)
			(stroke
				(width 0.1)
				(type default)
			)
			(layer "F.Fab")
		)
		(fp_line
			(start 0.3048 -0.1016)
			(end -0.3048 -0.1016)
			(stroke
				(width 0.1)
				(type default)
			)
			(layer "F.Fab")
		)
		(fp_line
			(start 0.3048 0.9906)
			(end 0.3048 -0.1016)
			(stroke
				(width 0.1)
				(type default)
			)
			(layer "F.Fab")
		)
		(pad "1" smd rect
			(at 0 0)
			(size 0.508 0.508)
			(layers "F.Cu" "F.Mask" "F.Paste")
			(net "VR_PVNN_P1V05_PCH_VD12")
		)
		(pad "2" smd rect
			(at 0 0.889)
			(size 0.508 0.508)
			(layers "F.Cu" "F.Mask" "F.Paste")
			(net "GND")
		)
		(zone
			(layer "F.Cu")
			(hatch none 0.5)
			(connect_pads
				(clearance 0)
			)
			(min_thickness 0.25)
			(keepout
				(tracks allowed)
				(vias not_allowed)
				(pads allowed)
				(copperpour not_allowed)
				(footprints allowed)
			)
			(placement
				(enabled no)
				(sheetname "")
			)
			(fill
				(thermal_gap 0.5)
				(thermal_bridge_width 0.5)
				(island_removal_mode 0)
			)
			(polygon
				(pts
					(xy 391.541 -150.982426) (xy 392.049 -150.982426) (xy 392.049 -150.601426) (xy 391.541 -150.601426)
				)
			)
		)
		(zone
			(layer "F.Cu")
			(hatch none 0.5)
			(connect_pads
				(clearance 0)
			)
			(min_thickness 0.25)
			(keepout
				(tracks not_allowed)
				(vias allowed)
				(pads allowed)
				(copperpour not_allowed)
				(footprints allowed)
			)
			(placement
				(enabled no)
				(sheetname "")
			)
			(fill
				(thermal_gap 0.5)
				(thermal_bridge_width 0.5)
				(island_removal_mode 0)
			)
			(polygon
				(pts
					(xy 391.541 -150.601426) (xy 392.049 -150.601426) (xy 392.049 -150.982426) (xy 391.541 -150.982426)
				)
			)
		)
	)
	(footprint ""
		(layer "F.Cu")
		(at 351.1804 -94.685104 90)
		(property "Reference" "C7C12"
			(at 0 0 90)
			(layer "F.SilkS")
			(hide yes)
			(effects
				(font
					(size 1.27 1.27)
				)
			)
		)
		(property "Value" ""
			(at 0 0 90)
			(layer "F.Fab")
			(effects
				(font
					(size 1.27 1.27)
				)
			)
		)
		(duplicate_pad_numbers_are_jumpers no)
		(fp_poly
			(pts
				(xy 0.3048 -0.1016) (xy 0.3048 0.9906) (xy -0.3048 0.9906) (xy -0.3048 -0.1016)
			)
			(stroke
				(width 0)
				(type default)
			)
			(fill no)
			(layer "F.CrtYd")
		)
		(fp_line
			(start 0.3048 -0.1016)
			(end -0.3048 -0.1016)
			(stroke
				(width 0.1)
				(type default)
			)
			(layer "F.Fab")
		)
		(fp_line
			(start -0.3048 -0.1016)
			(end -0.3048 0.9906)
			(stroke
				(width 0.1)
				(type default)
			)
			(layer "F.Fab")
		)
		(fp_line
			(start 0.3048 0.9906)
			(end 0.3048 -0.1016)
			(stroke
				(width 0.1)
				(type default)
			)
			(layer "F.Fab")
		)
		(fp_line
			(start -0.3048 0.9906)
			(end 0.3048 0.9906)
			(stroke
				(width 0.1)
				(type default)
			)
			(layer "F.Fab")
		)
		(pad "1" smd rect
			(at 0 0 90)
			(size 0.508 0.508)
			(layers "F.Cu" "F.Mask" "F.Paste")
			(net "VR_FET_SW_P12V_STBY_PVCCIO_CPU0")
		)
		(pad "2" smd rect
			(at 0 0.889 90)
			(size 0.508 0.508)
			(layers "F.Cu" "F.Mask" "F.Paste")
			(net "GND")
		)
		(zone
			(layer "F.Cu")
			(hatch none 0.5)
			(connect_pads
				(clearance 0)
			)
			(min_thickness 0.25)
			(keepout
				(tracks allowed)
				(vias not_allowed)
				(pads allowed)
				(copperpour not_allowed)
				(footprints allowed)
			)
			(placement
				(enabled no)
				(sheetname "")
			)
			(fill
				(thermal_gap 0.5)
				(thermal_bridge_width 0.5)
				(island_removal_mode 0)
			)
			(polygon
				(pts
					(xy 351.4344 -94.431104) (xy 351.4344 -94.939104) (xy 351.8154 -94.939104) (xy 351.8154 -94.431104)
				)
			)
		)
		(zone
			(layer "F.Cu")
			(hatch none 0.5)
			(connect_pads
				(clearance 0)
			)
			(min_thickness 0.25)
			(keepout
				(tracks not_allowed)
				(vias allowed)
				(pads allowed)
				(copperpour not_allowed)
				(footprints allowed)
			)
			(placement
				(enabled no)
				(sheetname "")
			)
			(fill
				(thermal_gap 0.5)
				(thermal_bridge_width 0.5)
				(island_removal_mode 0)
			)
			(polygon
				(pts
					(xy 351.8154 -94.431104) (xy 351.8154 -94.939104) (xy 351.4344 -94.939104) (xy 351.4344 -94.431104)
				)
			)
		)
	)
	(footprint ""
		(layer "F.Cu")
		(at 385.29514 -82.28076 180)
		(property "Reference" "R7W14"
			(at -0.8382 -0.67818 180)
			(unlocked yes)
			(layer "F.SilkS")
			(effects
				(font
					(size 0.4064 0.254)
					(thickness 0.1524)
				)
				(justify left)
			)
		)
		(property "Value" ""
			(at 0 0 180)
			(layer "F.Fab")
			(effects
				(font
					(size 1.27 1.27)
				)
			)
		)
		(duplicate_pad_numbers_are_jumpers no)
		(fp_poly
			(pts
				(xy -0.2794 -0.1016) (xy 0.2794 -0.1016) (xy 0.2794 0.9906) (xy -0.2794 0.9906)
			)
			(stroke
				(width 0)
				(type default)
			)
			(fill no)
			(layer "F.CrtYd")
		)
		(fp_line
			(start 0.2794 0.9906)
			(end 0.2794 -0.1016)
			(stroke
				(width 0.1)
				(type default)
			)
			(layer "F.Fab")
		)
		(fp_line
			(start 0.2794 -0.1016)
			(end -0.2794 -0.1016)
			(stroke
				(width 0.1)
				(type default)
			)
			(layer "F.Fab")
		)
		(fp_line
			(start -0.2794 0.9906)
			(end 0.2794 0.9906)
			(stroke
				(width 0.1)
				(type default)
			)
			(layer "F.Fab")
		)
		(fp_line
			(start -0.2794 -0.1016)
			(end -0.2794 0.9906)
			(stroke
				(width 0.1)
				(type default)
			)
			(layer "F.Fab")
		)
		(pad "1" smd rect
			(at 0 0 180)
			(size 0.508 0.508)
			(layers "F.Cu" "F.Mask" "F.Paste")
			(net "FM_BMC_READY_N")
		)
		(pad "2" smd rect
			(at 0 0.889 180)
			(size 0.508 0.508)
			(layers "F.Cu" "F.Mask" "F.Paste")
			(net "FM_BMC_READY_R1_N")
		)
		(zone
			(layer "F.Cu")
			(hatch none 0.5)
			(connect_pads
				(clearance 0)
			)
			(min_thickness 0.25)
			(keepout
				(tracks not_allowed)
				(vias allowed)
				(pads allowed)
				(copperpour not_allowed)
				(footprints allowed)
			)
			(placement
				(enabled no)
				(sheetname "")
			)
			(fill
				(thermal_gap 0.5)
				(thermal_bridge_width 0.5)
				(island_removal_mode 0)
			)
			(polygon
				(pts
					(xy 385.54914 -82.91576) (xy 385.04114 -82.91576) (xy 385.04114 -82.53476) (xy 385.54914 -82.53476)
				)
			)
		)
		(zone
			(layer "F.Cu")
			(hatch none 0.5)
			(connect_pads
				(clearance 0)
			)
			(min_thickness 0.25)
			(keepout
				(tracks allowed)
				(vias not_allowed)
				(pads allowed)
				(copperpour not_allowed)
				(footprints allowed)
			)
			(placement
				(enabled no)
				(sheetname "")
			)
			(fill
				(thermal_gap 0.5)
				(thermal_bridge_width 0.5)
				(island_removal_mode 0)
			)
			(polygon
				(pts
					(xy 385.54914 -82.53476) (xy 385.04114 -82.53476) (xy 385.04114 -82.91576) (xy 385.54914 -82.91576)
				)
			)
		)
	)
)
